(kicad_pcb
	(version 20260206)
	(generator "pcbnew")
	(generator_version "10.0")
	(general
		(thickness 1.6)
		(legacy_teardrops no)
	)
	(paper "A4")
	(title_block
		(title "Bryce Canyon_F.DPB_16315-1-OCP.brd")
		(comment 1 "Bryce Canyon / footprints 1933-1940 of 2223")
	)
	(layers
		(0 "F.Cu" signal "TOP")
		(4 "In1.Cu" signal "L2GND")
		(6 "In2.Cu" signal "L3")
		(8 "In3.Cu" signal "L4GND")
		(10 "In4.Cu" signal "L5")
		(12 "In5.Cu" signal "L6VCC")
		(14 "In6.Cu" signal "L7VCC")
		(16 "In7.Cu" signal "L8")
		(18 "In8.Cu" signal "L9GND")
		(20 "In9.Cu" signal "L10")
		(22 "In10.Cu" signal "L11GND")
		(2 "B.Cu" signal "BOTTOM")
		(9 "F.Adhes" user "F.Adhesive")
		(11 "B.Adhes" user "B.Adhesive")
		(13 "F.Paste" user "Package Geometry/Pastemask Top")
		(15 "B.Paste" user "Package Geometry/Pastemask Bottom")
		(5 "F.SilkS" user "Ref Des/Silkscreen Top")
		(7 "B.SilkS" user "Ref Des/Silkscreen Bottom")
		(1 "F.Mask" user "Board Geometry/Soldermask Top")
		(3 "B.Mask" user "Board Geometry/Soldermask Bottom")
		(17 "Dwgs.User" user "User.Drawings")
		(19 "Cmts.User" user "User.Comments")
		(21 "Eco1.User" user "User.Eco1")
		(23 "Eco2.User" user "User.Eco2")
		(25 "Edge.Cuts" user "Board Geometry/Outline")
		(27 "Margin" user)
		(31 "F.CrtYd" user "Package Geometry/Place Bound Top")
		(29 "B.CrtYd" user "Package Geometry/Place Bound Bottom")
		(35 "F.Fab" user "Ref Des/Assembly Top")
		(33 "B.Fab" user "Ref Des/Assembly Bottom")
	)
	(footprint ""
		(layer "F.Cu")
		(at 14.715998 -294.683942 -90)
		(property "Reference" "C512"
			(at 0 0 270)
			(layer "F.SilkS")
			(hide yes)
			(effects
				(font
					(size 1.27 1.27)
				)
			)
		)
		(property "Value" "SC4D7U25V5KX-1-GP"
			(at -0.0762 -6.1214 270)
			(unlocked yes)
			(layer "F.Fab")
			(hide yes)
			(effects
				(font
					(size 1.016 1.016)
					(thickness 0.1524)
				)
			)
		)
		(property "Device Type" "C805H58"
			(at -0.0762 -8.1534 270)
			(unlocked yes)
			(layer "F.Fab")
			(hide yes)
			(effects
				(font
					(size 1.016 1.016)
					(thickness 0.1524)
				)
			)
		)
		(duplicate_pad_numbers_are_jumpers no)
		(fp_line
			(start 0.635 0)
			(end -0.635 0)
			(stroke
				(width 0.508)
				(type default)
			)
			(layer "F.SilkS")
		)
		(fp_rect
			(start -0.9652 1.778)
			(end 0.9652 -1.778)
			(stroke
				(width 0)
				(type default)
			)
			(fill no)
			(layer "F.CrtYd")
		)
		(fp_poly
			(pts
				(xy -0.9652 -1.778) (xy 0.9652 -1.778) (xy 0.9652 1.778) (xy -0.9652 1.778)
			)
			(stroke
				(width 0)
				(type default)
			)
			(fill no)
			(layer "F.Fab")
		)
		(pad "1" smd rect
			(at 0 -0.9652 270)
			(size 1.397 1.143)
			(layers "F.Cu" "F.Mask" "F.Paste")
			(net "P12V_HDD0")
		)
		(pad "2" smd rect
			(at 0 0.9652 270)
			(size 1.397 1.143)
			(layers "F.Cu" "F.Mask" "F.Paste")
			(net "GND")
		)
	)
	(footprint ""
		(layer "F.Cu")
		(at 377.594876 -127.254)
		(property "Reference" "R332"
			(at 0 0 0)
			(layer "F.SilkS")
			(hide yes)
			(effects
				(font
					(size 1.27 1.27)
				)
			)
		)
		(property "Value" "130R3F-GP"
			(at -0.0254 -2.5146 0)
			(unlocked yes)
			(layer "F.Fab")
			(hide yes)
			(effects
				(font
					(size 1.016 1.016)
					(thickness 0.1524)
				)
			)
		)
		(property "Device Type" "R603H22"
			(at -0.0254 -4.0386 0)
			(unlocked yes)
			(layer "F.Fab")
			(hide yes)
			(effects
				(font
					(size 1.016 1.016)
					(thickness 0.1524)
				)
			)
		)
		(duplicate_pad_numbers_are_jumpers no)
		(fp_line
			(start -0.4826 0)
			(end -0.2032 0)
			(stroke
				(width 0.2032)
				(type default)
			)
			(layer "F.SilkS")
		)
		(fp_line
			(start 0.2032 0)
			(end 0.4826 0)
			(stroke
				(width 0.2032)
				(type default)
			)
			(layer "F.SilkS")
		)
		(fp_rect
			(start -0.5842 1.3335)
			(end 0.5842 -1.3335)
			(stroke
				(width 0)
				(type default)
			)
			(fill no)
			(layer "F.CrtYd")
		)
		(fp_rect
			(start -0.5842 1.3335)
			(end 0.5842 -1.3335)
			(stroke
				(width 0)
				(type default)
			)
			(fill no)
			(layer "F.Fab")
		)
		(pad "1" smd custom
			(at 0 -0.762)
			(size 0.2159 0.2159)
			(layers "F.Cu" "F.Mask" "F.Paste")
			(net "P5V_A_3")
			(options
				(clearance outline)
				(anchor circle)
			)
			(primitives
				(gr_poly
					(pts
						(arc
							(start -0.3302 -0.4318)
							(mid -0.402042 -0.402042)
							(end -0.4318 -0.3302)
						)
						(arc
							(start -0.4318 0.3302)
							(mid -0.402042 0.402042)
							(end -0.3302 0.4318)
						)
						(arc
							(start 0.3302 0.4318)
							(mid 0.402042 0.402042)
							(end 0.4318 0.3302)
						)
						(arc
							(start 0.4318 -0.3302)
							(mid 0.402042 -0.402042)
							(end 0.3302 -0.4318)
						)
					)
					(width 0)
					(fill yes)
				)
			)
		)
		(pad "2" smd custom
			(at 0 0.762)
			(size 0.2159 0.2159)
			(layers "F.Cu" "F.Mask" "F.Paste")
			(net "FLT_HDD20")
			(options
				(clearance outline)
				(anchor circle)
			)
			(primitives
				(gr_poly
					(pts
						(arc
							(start -0.3302 -0.4318)
							(mid -0.402042 -0.402042)
							(end -0.4318 -0.3302)
						)
						(arc
							(start -0.4318 0.3302)
							(mid -0.402042 0.402042)
							(end -0.3302 0.4318)
						)
						(arc
							(start 0.3302 0.4318)
							(mid 0.402042 0.402042)
							(end 0.4318 0.3302)
						)
						(arc
							(start 0.4318 -0.3302)
							(mid 0.402042 -0.402042)
							(end 0.3302 -0.4318)
						)
					)
					(width 0)
					(fill yes)
				)
			)
		)
	)
	(footprint ""
		(layer "F.Cu")
		(at 87.340948 -74.462894 180)
		(property "Reference" "C385"
			(at 0 0 180)
			(layer "F.SilkS")
			(hide yes)
			(effects
				(font
					(size 1.27 1.27)
				)
			)
		)
		(property "Value" "SC1U25V3KX-GP"
			(at 0 -2.8194 180)
			(unlocked yes)
			(layer "F.Fab")
			(hide yes)
			(effects
				(font
					(size 1.016 1.016)
					(thickness 0.1524)
				)
			)
		)
		(property "Device Type" "C603H36"
			(at 0 -4.3434 180)
			(unlocked yes)
			(layer "F.Fab")
			(hide yes)
			(effects
				(font
					(size 1.016 1.016)
					(thickness 0.1524)
				)
			)
		)
		(duplicate_pad_numbers_are_jumpers no)
		(fp_line
			(start 0.508 0)
			(end -0.508 0)
			(stroke
				(width 0.2032)
				(type default)
			)
			(layer "F.SilkS")
		)
		(fp_rect
			(start -0.5842 1.3335)
			(end 0.5842 -1.3335)
			(stroke
				(width 0)
				(type default)
			)
			(fill no)
			(layer "F.CrtYd")
		)
		(fp_rect
			(start -0.5842 1.3335)
			(end 0.5842 -1.3335)
			(stroke
				(width 0)
				(type default)
			)
			(fill no)
			(layer "F.Fab")
		)
		(pad "1" smd custom
			(at 0 -0.762 180)
			(size 0.2159 0.2159)
			(layers "F.Cu" "F.Mask" "F.Paste")
			(net "P12V_HDD26")
			(options
				(clearance outline)
				(anchor circle)
			)
			(primitives
				(gr_poly
					(pts
						(arc
							(start -0.3302 -0.4318)
							(mid -0.402042 -0.402042)
							(end -0.4318 -0.3302)
						)
						(arc
							(start -0.4318 0.3302)
							(mid -0.402042 0.402042)
							(end -0.3302 0.4318)
						)
						(arc
							(start 0.3302 0.4318)
							(mid 0.402042 0.402042)
							(end 0.4318 0.3302)
						)
						(arc
							(start 0.4318 -0.3302)
							(mid 0.402042 -0.402042)
							(end 0.3302 -0.4318)
						)
					)
					(width 0)
					(fill yes)
				)
			)
		)
		(pad "2" smd custom
			(at 0 0.762 180)
			(size 0.2159 0.2159)
			(layers "F.Cu" "F.Mask" "F.Paste")
			(net "GND")
			(options
				(clearance outline)
				(anchor circle)
			)
			(primitives
				(gr_poly
					(pts
						(arc
							(start -0.3302 -0.4318)
							(mid -0.402042 -0.402042)
							(end -0.4318 -0.3302)
						)
						(arc
							(start -0.4318 0.3302)
							(mid -0.402042 0.402042)
							(end -0.3302 0.4318)
						)
						(arc
							(start 0.3302 0.4318)
							(mid 0.402042 0.402042)
							(end 0.4318 0.3302)
						)
						(arc
							(start 0.4318 -0.3302)
							(mid 0.402042 -0.402042)
							(end 0.3302 -0.4318)
						)
					)
					(width 0)
					(fill yes)
				)
			)
		)
	)
	(footprint ""
		(layer "F.Cu")
		(at 230.8606 -391.033 -90)
		(property "Reference" "R1148"
			(at 0 0 270)
			(layer "F.SilkS")
			(hide yes)
			(effects
				(font
					(size 1.27 1.27)
				)
			)
		)
		(property "Value" "0R0603-PAD-2-GP-U"
			(at 2.1209 -0.1397 270)
			(unlocked yes)
			(layer "F.Fab")
			(hide yes)
			(effects
				(font
					(size 1.016 1.016)
					(thickness 0.1524)
				)
			)
		)
		(property "Device Type" "0R0603-PAD-1-U"
			(at 2.1209 -1.6637 270)
			(unlocked yes)
			(layer "F.Fab")
			(hide yes)
			(effects
				(font
					(size 1.016 1.016)
					(thickness 0.1524)
				)
			)
		)
		(duplicate_pad_numbers_are_jumpers no)
		(fp_rect
			(start -0.5842 1.3335)
			(end 0.5842 -1.3335)
			(stroke
				(width 0)
				(type default)
			)
			(fill no)
			(layer "F.CrtYd")
		)
		(fp_rect
			(start -0.5842 1.3335)
			(end 0.5842 -1.3335)
			(stroke
				(width 0)
				(type default)
			)
			(fill no)
			(layer "F.Fab")
		)
		(pad "1" smd custom
			(at 0 -0.762 270)
			(size 0.2159 0.2159)
			(layers "F.Cu" "F.Mask" "F.Paste")
			(net "AGND_CURRENT_DPB")
			(options
				(clearance outline)
				(anchor circle)
			)
			(primitives
				(gr_poly
					(pts
						(arc
							(start -0.3302 -0.5842)
							(mid -0.402042 -0.554442)
							(end -0.4318 -0.4826)
						)
						(arc
							(start -0.4318 0.4826)
							(mid -0.402042 0.554442)
							(end -0.3302 0.5842)
						)
						(arc
							(start 0.3302 0.5842)
							(mid 0.402042 0.554442)
							(end 0.4318 0.4826)
						)
						(arc
							(start 0.4318 -0.4826)
							(mid 0.402042 -0.554442)
							(end 0.3302 -0.5842)
						)
					)
					(width 0)
					(fill yes)
				)
			)
		)
		(pad "2" smd custom
			(at 0 0.762 270)
			(size 0.2159 0.2159)
			(layers "F.Cu" "F.Mask" "F.Paste")
			(net "GND")
			(options
				(clearance outline)
				(anchor circle)
			)
			(primitives
				(gr_poly
					(pts
						(arc
							(start -0.4318 0.4826)
							(mid -0.402042 0.554442)
							(end -0.3302 0.5842)
						)
						(arc
							(start 0.3302 0.5842)
							(mid 0.402042 0.554442)
							(end 0.4318 0.4826)
						)
						(arc
							(start 0.4318 -0.4826)
							(mid 0.402042 -0.554442)
							(end 0.3302 -0.5842)
						)
						(arc
							(start -0.3302 -0.5842)
							(mid -0.402042 -0.554442)
							(end -0.4318 -0.4826)
						)
					)
					(width 0)
					(fill yes)
				)
			)
		)
	)
	(footprint ""
		(layer "F.Cu")
		(at 49.215802 -149.79015 -90)
		(property "Reference" "R1227"
			(at 0 0 270)
			(layer "F.SilkS")
			(hide yes)
			(effects
				(font
					(size 1.27 1.27)
				)
			)
		)
		(property "Value" "10KR2F-2-GP"
			(at 0.064008 -3.993896 270)
			(unlocked yes)
			(layer "F.Fab")
			(hide yes)
			(effects
				(font
					(size 1.016 1.016)
					(thickness 0.1524)
				)
			)
		)
		(property "Device Type" "R402H16"
			(at 0.064008 -5.517896 270)
			(unlocked yes)
			(layer "F.Fab")
			(hide yes)
			(effects
				(font
					(size 1.016 1.016)
					(thickness 0.1524)
				)
			)
		)
		(duplicate_pad_numbers_are_jumpers no)
		(fp_line
			(start -0.508 -0.9398)
			(end -0.508 0.9398)
			(stroke
				(width 0.1524)
				(type default)
			)
			(layer "F.SilkS")
		)
		(fp_line
			(start 0.508 -0.9398)
			(end -0.508 -0.9398)
			(stroke
				(width 0.1524)
				(type default)
			)
			(layer "F.SilkS")
		)
		(fp_rect
			(start -0.508 0.9398)
			(end 0.508 -0.9398)
			(stroke
				(width 0)
				(type default)
			)
			(fill no)
			(layer "F.CrtYd")
		)
		(fp_rect
			(start -0.508 0.9398)
			(end 0.508 -0.9398)
			(stroke
				(width 0)
				(type default)
			)
			(fill no)
			(layer "F.Fab")
		)
		(pad "1" smd custom
			(at 0 -0.4445 270)
			(size 0.1397 0.1397)
			(layers "F.Cu" "F.Mask" "F.Paste")
			(net "P5V_B_EN_R")
			(options
				(clearance outline)
				(anchor circle)
			)
			(primitives
				(gr_poly
					(pts
						(arc
							(start -0.1778 -0.2794)
							(mid -0.249642 -0.249642)
							(end -0.2794 -0.1778)
						)
						(arc
							(start -0.2794 0.1778)
							(mid -0.249642 0.249642)
							(end -0.1778 0.2794)
						)
						(arc
							(start 0.1778 0.2794)
							(mid 0.249642 0.249642)
							(end 0.2794 0.1778)
						)
						(arc
							(start 0.2794 -0.1778)
							(mid 0.249642 -0.249642)
							(end 0.1778 -0.2794)
						)
					)
					(width 0)
					(fill yes)
				)
			)
		)
		(pad "2" smd custom
			(at 0 0.4445 270)
			(size 0.1397 0.1397)
			(layers "F.Cu" "F.Mask" "F.Paste")
			(net "GND")
			(options
				(clearance outline)
				(anchor circle)
			)
			(primitives
				(gr_poly
					(pts
						(arc
							(start -0.1778 -0.2794)
							(mid -0.249642 -0.249642)
							(end -0.2794 -0.1778)
						)
						(arc
							(start -0.2794 0.1778)
							(mid -0.249642 0.249642)
							(end -0.1778 0.2794)
						)
						(arc
							(start 0.1778 0.2794)
							(mid 0.249642 0.249642)
							(end 0.2794 0.1778)
						)
						(arc
							(start 0.2794 -0.1778)
							(mid 0.249642 -0.249642)
							(end 0.1778 -0.2794)
						)
					)
					(width 0)
					(fill yes)
				)
			)
		)
	)
	(footprint ""
		(layer "F.Cu")
		(at 363.655102 -42.585894)
		(property "Reference" "R855"
			(at 0 0 0)
			(layer "F.SilkS")
			(hide yes)
			(effects
				(font
					(size 1.27 1.27)
				)
			)
		)
		(property "Value" "4K7R2J-2-GP"
			(at 0.064008 -3.993896 0)
			(unlocked yes)
			(layer "F.Fab")
			(hide yes)
			(effects
				(font
					(size 1.016 1.016)
					(thickness 0.1524)
				)
			)
		)
		(property "Device Type" "R402H16"
			(at 0.064008 -5.517896 0)
			(unlocked yes)
			(layer "F.Fab")
			(hide yes)
			(effects
				(font
					(size 1.016 1.016)
					(thickness 0.1524)
				)
			)
		)
		(duplicate_pad_numbers_are_jumpers no)
		(fp_line
			(start -0.508 -0.9398)
			(end -0.508 0.9398)
			(stroke
				(width 0.1524)
				(type default)
			)
			(layer "F.SilkS")
		)
		(fp_line
			(start 0.508 -0.9398)
			(end -0.508 -0.9398)
			(stroke
				(width 0.1524)
				(type default)
			)
			(layer "F.SilkS")
		)
		(fp_rect
			(start -0.508 0.9398)
			(end 0.508 -0.9398)
			(stroke
				(width 0)
				(type default)
			)
			(fill no)
			(layer "F.CrtYd")
		)
		(fp_rect
			(start -0.508 0.9398)
			(end 0.508 -0.9398)
			(stroke
				(width 0)
				(type default)
			)
			(fill no)
			(layer "F.Fab")
		)
		(pad "1" smd custom
			(at 0 -0.4445)
			(size 0.1397 0.1397)
			(layers "F.Cu" "F.Mask" "F.Paste")
			(net "SW_PWR_R_HDD31")
			(options
				(clearance outline)
				(anchor circle)
			)
			(primitives
				(gr_poly
					(pts
						(arc
							(start -0.1778 -0.2794)
							(mid -0.249642 -0.249642)
							(end -0.2794 -0.1778)
						)
						(arc
							(start -0.2794 0.1778)
							(mid -0.249642 0.249642)
							(end -0.1778 0.2794)
						)
						(arc
							(start 0.1778 0.2794)
							(mid 0.249642 0.249642)
							(end 0.2794 0.1778)
						)
						(arc
							(start 0.2794 -0.1778)
							(mid 0.249642 -0.249642)
							(end 0.1778 -0.2794)
						)
					)
					(width 0)
					(fill yes)
				)
			)
		)
		(pad "2" smd custom
			(at 0 0.4445)
			(size 0.1397 0.1397)
			(layers "F.Cu" "F.Mask" "F.Paste")
			(net "GND")
			(options
				(clearance outline)
				(anchor circle)
			)
			(primitives
				(gr_poly
					(pts
						(arc
							(start -0.1778 -0.2794)
							(mid -0.249642 -0.249642)
							(end -0.2794 -0.1778)
						)
						(arc
							(start -0.2794 0.1778)
							(mid -0.249642 0.249642)
							(end -0.1778 0.2794)
						)
						(arc
							(start 0.1778 0.2794)
							(mid 0.249642 0.249642)
							(end 0.2794 0.1778)
						)
						(arc
							(start 0.2794 -0.1778)
							(mid 0.249642 -0.249642)
							(end 0.1778 -0.2794)
						)
					)
					(width 0)
					(fill yes)
				)
			)
		)
	)
	(footprint ""
		(layer "F.Cu")
		(at 298.831 -284.099)
		(property "Reference" "R10"
			(at 0 0 0)
			(layer "F.SilkS")
			(hide yes)
			(effects
				(font
					(size 1.27 1.27)
				)
			)
		)
		(property "Value" "0R2J-2-GP"
			(at 0.064008 -3.993896 0)
			(unlocked yes)
			(layer "F.Fab")
			(hide yes)
			(effects
				(font
					(size 1.016 1.016)
					(thickness 0.1524)
				)
			)
		)
		(property "Device Type" "R402H16"
			(at 0.064008 -5.517896 0)
			(unlocked yes)
			(layer "F.Fab")
			(hide yes)
			(effects
				(font
					(size 1.016 1.016)
					(thickness 0.1524)
				)
			)
		)
		(duplicate_pad_numbers_are_jumpers no)
		(fp_line
			(start -0.508 -0.9398)
			(end -0.508 0.9398)
			(stroke
				(width 0.1524)
				(type default)
			)
			(layer "F.SilkS")
		)
		(fp_line
			(start 0.508 -0.9398)
			(end -0.508 -0.9398)
			(stroke
				(width 0.1524)
				(type default)
			)
			(layer "F.SilkS")
		)
		(fp_rect
			(start -0.508 0.9398)
			(end 0.508 -0.9398)
			(stroke
				(width 0)
				(type default)
			)
			(fill no)
			(layer "F.CrtYd")
		)
		(fp_rect
			(start -0.508 0.9398)
			(end 0.508 -0.9398)
			(stroke
				(width 0)
				(type default)
			)
			(fill no)
			(layer "F.Fab")
		)
		(pad "1" smd custom
			(at 0 -0.4445)
			(size 0.1397 0.1397)
			(layers "F.Cu" "F.Mask" "F.Paste")
			(net "SCC_A_HS_EN")
			(options
				(clearance outline)
				(anchor circle)
			)
			(primitives
				(gr_poly
					(pts
						(arc
							(start -0.1778 -0.2794)
							(mid -0.249642 -0.249642)
							(end -0.2794 -0.1778)
						)
						(arc
							(start -0.2794 0.1778)
							(mid -0.249642 0.249642)
							(end -0.1778 0.2794)
						)
						(arc
							(start 0.1778 0.2794)
							(mid 0.249642 0.249642)
							(end 0.2794 0.1778)
						)
						(arc
							(start 0.2794 -0.1778)
							(mid 0.249642 -0.249642)
							(end 0.1778 -0.2794)
						)
					)
					(width 0)
					(fill yes)
				)
			)
		)
		(pad "2" smd custom
			(at 0 0.4445)
			(size 0.1397 0.1397)
			(layers "F.Cu" "F.Mask" "F.Paste")
			(net "GND")
			(options
				(clearance outline)
				(anchor circle)
			)
			(primitives
				(gr_poly
					(pts
						(arc
							(start -0.1778 -0.2794)
							(mid -0.249642 -0.249642)
							(end -0.2794 -0.1778)
						)
						(arc
							(start -0.2794 0.1778)
							(mid -0.249642 0.249642)
							(end -0.1778 0.2794)
						)
						(arc
							(start 0.1778 0.2794)
							(mid 0.249642 0.249642)
							(end 0.2794 0.1778)
						)
						(arc
							(start 0.2794 -0.1778)
							(mid 0.249642 -0.249642)
							(end 0.1778 -0.2794)
						)
					)
					(width 0)
					(fill yes)
				)
			)
		)
	)
	(footprint ""
		(layer "F.Cu")
		(at 478.832926 -177.270918)
		(property "Reference" "R658"
			(at 0 0 0)
			(layer "F.SilkS")
			(hide yes)
			(effects
				(font
					(size 1.27 1.27)
				)
			)
		)
		(property "Value" "2R6F-GP"
			(at -0.0508 -4.8514 0)
			(unlocked yes)
			(layer "F.Fab")
			(hide yes)
			(effects
				(font
					(size 1.016 1.016)
					(thickness 0.1524)
				)
			)
		)
		(property "Device Type" "R1206H26"
			(at 0 -6.3754 0)
			(unlocked yes)
			(layer "F.Fab")
			(hide yes)
			(effects
				(font
					(size 1.016 1.016)
					(thickness 0.1524)
				)
			)
		)
		(duplicate_pad_numbers_are_jumpers no)
		(fp_line
			(start -1.016 -2.2352)
			(end 1.016 -2.2352)
			(stroke
				(width 0.1524)
				(type default)
			)
			(layer "F.SilkS")
		)
		(fp_line
			(start -1.016 2.2352)
			(end -1.016 -2.2352)
			(stroke
				(width 0.1524)
				(type default)
			)
			(layer "F.SilkS")
		)
		(fp_line
			(start 1.016 -2.2352)
			(end 1.016 2.2352)
			(stroke
				(width 0.1524)
				(type default)
			)
			(layer "F.SilkS")
		)
		(fp_line
			(start 1.016 2.2352)
			(end -1.016 2.2352)
			(stroke
				(width 0.1524)
				(type default)
			)
			(layer "F.SilkS")
		)
		(fp_rect
			(start -1.0922 2.3114)
			(end 1.0922 -2.3114)
			(stroke
				(width 0)
				(type default)
			)
			(fill no)
			(layer "F.CrtYd")
		)
		(fp_poly
			(pts
				(xy -1.0922 -2.3114) (xy 1.0922 -2.3114) (xy 1.0922 2.3114) (xy -1.0922 2.3114)
			)
			(stroke
				(width 0)
				(type default)
			)
			(fill no)
			(layer "F.Fab")
		)
		(pad "1" smd rect
			(at 0 -1.397)
			(size 1.651 1.27)
			(layers "F.Cu" "F.Mask" "F.Paste")
			(net "P5V_HDD23")
		)
		(pad "2" smd rect
			(at 0 1.397)
			(size 1.651 1.27)
			(layers "F.Cu" "F.Mask" "F.Paste")
			(net "5V_PRE_23")
		)
	)
)
